# SCM (Grand Teton) — schematic netlist excerpt (pin names and nets, part order shuffled) for the footprints in the layout excerpt that follows; sources: Cadence DE-HDL packaged netlist, KiCad conversion of 12092022_DA0F0TMDCD0_F0T_Management_Board_D_brd_V3_OCP.brd

R902  Q_RES  0 5% CHIP  pkg 0402LF  page 31 : A = UART_BIC_DBG_RX ; B = UART_BIC_DBG_RX_R
R273  Q_RES  100K 1% CHIP  pkg 0402LF  page 13 : A = PD_CLK_125M_PHY_BMC_RGMII ; B = GND

(kicad_pcb
	(version 20260206)
	(generator "pcbnew")
	(generator_version "10.0")
	(general
		(thickness 1.6)
		(legacy_teardrops no)
	)
	(paper "A4")
	(title_block
		(title "12092022_DA0F0TMDCD0_F0T_Management_Board_D_brd_V3_OCP.brd")
		(comment 1 "Grand Teton / footprints 39-40 of 1440")
	)
	(layers
		(0 "F.Cu" signal "TOP")
		(4 "In1.Cu" signal "GND")
		(6 "In2.Cu" signal "IN1")
		(8 "In3.Cu" signal "GND1")
		(10 "In4.Cu" signal "IN2")
		(12 "In5.Cu" signal "VCC")
		(14 "In6.Cu" signal "VCC1")
		(16 "In7.Cu" signal "IN3")
		(18 "In8.Cu" signal "GND2")
		(20 "In9.Cu" signal "IN4")
		(22 "In10.Cu" signal "GND3")
		(2 "B.Cu" signal "BOTTOM")
		(9 "F.Adhes" user "F.Adhesive")
		(11 "B.Adhes" user "B.Adhesive")
		(13 "F.Paste" user "Package Geometry/Pastemask Top")
		(15 "B.Paste" user "Package Geometry/Pastemask Bottom")
		(5 "F.SilkS" user "Ref Des/Silkscreen Top")
		(7 "B.SilkS" user "Ref Des/Silkscreen Bottom")
		(1 "F.Mask" user "Board Geometry/Soldermask Top")
		(3 "B.Mask" user "Board Geometry/Soldermask Bottom")
		(17 "Dwgs.User" user "User.Drawings")
		(19 "Cmts.User" user "User.Comments")
		(21 "Eco1.User" user "User.Eco1")
		(23 "Eco2.User" user "User.Eco2")
		(25 "Edge.Cuts" user "Board Geometry/Outline")
		(27 "Margin" user)
		(31 "F.CrtYd" user "Package Geometry/Place Bound Top")
		(29 "B.CrtYd" user "Package Geometry/Place Bound Bottom")
		(35 "F.Fab" user "Ref Des/Assembly Top")
		(33 "B.Fab" user "Ref Des/Assembly Bottom")
	)
	(footprint ""
		(layer "F.Cu")
		(at 61.8998 -27.3304 -90)
		(property "Reference" "R273"
			(at 0 0 270)
			(layer "F.SilkS")
			(hide yes)
			(effects
				(font
					(size 1.27 1.27)
				)
			)
		)
		(property "Value" ""
			(at 0 0 270)
			(layer "F.Fab")
			(effects
				(font
					(size 1.27 1.27)
				)
			)
		)
		(duplicate_pad_numbers_are_jumpers no)
		(fp_line
			(start -0.7874 0.4064)
			(end -0.7874 -0.4064)
			(stroke
				(width 0.1524)
				(type default)
			)
			(layer "F.SilkS")
		)
		(fp_line
			(start 0.7874 0.4064)
			(end -0.7874 0.4064)
			(stroke
				(width 0.1524)
				(type default)
			)
			(layer "F.SilkS")
		)
		(fp_line
			(start -0.7874 -0.4064)
			(end 0.7874 -0.4064)
			(stroke
				(width 0.1524)
				(type default)
			)
			(layer "F.SilkS")
		)
		(fp_line
			(start 0.7874 -0.4064)
			(end 0.7874 0.4064)
			(stroke
				(width 0.1524)
				(type default)
			)
			(layer "F.SilkS")
		)
		(fp_line
			(start -0.67945 0.3048)
			(end -0.67945 -0.305054)
			(stroke
				(width 0.1)
				(type default)
			)
			(layer "F.Fab")
		)
		(fp_line
			(start -0.12065 0.3048)
			(end -0.67945 0.3048)
			(stroke
				(width 0.1)
				(type default)
			)
			(layer "F.Fab")
		)
		(fp_line
			(start 0.120396 0.3048)
			(end 0.120396 0.2794)
			(stroke
				(width 0.1)
				(type default)
			)
			(layer "F.Fab")
		)
		(fp_line
			(start 0.67945 0.3048)
			(end 0.120396 0.3048)
			(stroke
				(width 0.1)
				(type default)
			)
			(layer "F.Fab")
		)
		(fp_line
			(start -0.12065 0.2794)
			(end -0.12065 0.3048)
			(stroke
				(width 0.1)
				(type default)
			)
			(layer "F.Fab")
		)
		(fp_line
			(start 0.120396 0.2794)
			(end -0.12065 0.2794)
			(stroke
				(width 0.1)
				(type default)
			)
			(layer "F.Fab")
		)
		(fp_line
			(start -0.12065 -0.2794)
			(end 0.12065 -0.2794)
			(stroke
				(width 0.1)
				(type default)
			)
			(layer "F.Fab")
		)
		(fp_line
			(start 0.12065 -0.2794)
			(end 0.12065 -0.3048)
			(stroke
				(width 0.1)
				(type default)
			)
			(layer "F.Fab")
		)
		(fp_line
			(start 0.12065 -0.3048)
			(end 0.67945 -0.3048)
			(stroke
				(width 0.1)
				(type default)
			)
			(layer "F.Fab")
		)
		(fp_line
			(start 0.67945 -0.3048)
			(end 0.67945 0.3048)
			(stroke
				(width 0.1)
				(type default)
			)
			(layer "F.Fab")
		)
		(fp_line
			(start -0.67945 -0.305054)
			(end -0.12065 -0.305054)
			(stroke
				(width 0.1)
				(type default)
			)
			(layer "F.Fab")
		)
		(fp_line
			(start -0.12065 -0.305054)
			(end -0.12065 -0.2794)
			(stroke
				(width 0.1)
				(type default)
			)
			(layer "F.Fab")
		)
		(pad "1" smd circle
			(at -0.40005 0 270)
			(size 0 0)
			(layers "F.Cu" "F.Mask" "F.Paste")
			(net "PD_CLK_125M_PHY_BMC_RGMII")
		)
		(pad "2" smd circle
			(at 0.40005 0 270)
			(size 0 0)
			(layers "F.Cu" "F.Mask" "F.Paste")
			(net "GND")
		)
	)
	(footprint ""
		(layer "F.Cu")
		(at 15.548864 -57.7342 90)
		(property "Reference" "R902"
			(at 0 0 90)
			(layer "F.SilkS")
			(hide yes)
			(effects
				(font
					(size 1.27 1.27)
				)
			)
		)
		(property "Value" ""
			(at 0 0 90)
			(layer "F.Fab")
			(effects
				(font
					(size 1.27 1.27)
				)
			)
		)
		(duplicate_pad_numbers_are_jumpers no)
		(fp_line
			(start 0.7874 -0.4064)
			(end 0.7874 0.4064)
			(stroke
				(width 0.1524)
				(type default)
			)
			(layer "F.SilkS")
		)
		(fp_line
			(start -0.7874 -0.4064)
			(end 0.7874 -0.4064)
			(stroke
				(width 0.1524)
				(type default)
			)
			(layer "F.SilkS")
		)
		(fp_line
			(start 0.7874 0.4064)
			(end -0.7874 0.4064)
			(stroke
				(width 0.1524)
				(type default)
			)
			(layer "F.SilkS")
		)
		(fp_line
			(start -0.7874 0.4064)
			(end -0.7874 -0.4064)
			(stroke
				(width 0.1524)
				(type default)
			)
			(layer "F.SilkS")
		)
		(fp_line
			(start -0.12065 -0.305054)
			(end -0.12065 -0.2794)
			(stroke
				(width 0.1)
				(type default)
			)
			(layer "F.Fab")
		)
		(fp_line
			(start -0.67945 -0.305054)
			(end -0.12065 -0.305054)
			(stroke
				(width 0.1)
				(type default)
			)
			(layer "F.Fab")
		)
		(fp_line
			(start 0.67945 -0.3048)
			(end 0.67945 0.3048)
			(stroke
				(width 0.1)
				(type default)
			)
			(layer "F.Fab")
		)
		(fp_line
			(start 0.12065 -0.3048)
			(end 0.67945 -0.3048)
			(stroke
				(width 0.1)
				(type default)
			)
			(layer "F.Fab")
		)
		(fp_line
			(start 0.12065 -0.2794)
			(end 0.12065 -0.3048)
			(stroke
				(width 0.1)
				(type default)
			)
			(layer "F.Fab")
		)
		(fp_line
			(start -0.12065 -0.2794)
			(end 0.12065 -0.2794)
			(stroke
				(width 0.1)
				(type default)
			)
			(layer "F.Fab")
		)
		(fp_line
			(start 0.120396 0.2794)
			(end -0.12065 0.2794)
			(stroke
				(width 0.1)
				(type default)
			)
			(layer "F.Fab")
		)
		(fp_line
			(start -0.12065 0.2794)
			(end -0.12065 0.3048)
			(stroke
				(width 0.1)
				(type default)
			)
			(layer "F.Fab")
		)
		(fp_line
			(start 0.67945 0.3048)
			(end 0.120396 0.3048)
			(stroke
				(width 0.1)
				(type default)
			)
			(layer "F.Fab")
		)
		(fp_line
			(start 0.120396 0.3048)
			(end 0.120396 0.2794)
			(stroke
				(width 0.1)
				(type default)
			)
			(layer "F.Fab")
		)
		(fp_line
			(start -0.12065 0.3048)
			(end -0.67945 0.3048)
			(stroke
				(width 0.1)
				(type default)
			)
			(layer "F.Fab")
		)
		(fp_line
			(start -0.67945 0.3048)
			(end -0.67945 -0.305054)
			(stroke
				(width 0.1)
				(type default)
			)
			(layer "F.Fab")
		)
		(pad "1" smd circle
			(at -0.40005 0 90)
			(size 0 0)
			(layers "F.Cu" "F.Mask" "F.Paste")
			(net "UART_BIC_DBG_RX")
		)
		(pad "2" smd circle
			(at 0.40005 0 90)
			(size 0 0)
			(layers "F.Cu" "F.Mask" "F.Paste")
			(net "UART_BIC_DBG_RX_R")
		)
	)
)
